(kicad_pcb
	(version 20260206)
	(generator "pcbnew")
	(generator_version "10.0")
	(general
		(thickness 1.6)
		(legacy_teardrops no)
	)
	(paper "A4")
	(title_block
		(title "Bryce Canyon_IOM_IOC_16318-2_OCP.brd")
		(comment 1 "Bryce Canyon / footprints 13-19 of 1605")
	)
	(layers
		(0 "F.Cu" signal "TOP")
		(4 "In1.Cu" signal "L2GND")
		(6 "In2.Cu" signal "L3")
		(8 "In3.Cu" signal "L4VCC")
		(10 "In4.Cu" signal "L5VCC")
		(12 "In5.Cu" signal "L6")
		(14 "In6.Cu" signal "L7GND")
		(2 "B.Cu" signal "BOTTOM")
		(9 "F.Adhes" user "F.Adhesive")
		(11 "B.Adhes" user "B.Adhesive")
		(13 "F.Paste" user "Package Geometry/Pastemask Top")
		(15 "B.Paste" user "Package Geometry/Pastemask Bottom")
		(5 "F.SilkS" user "Ref Des/Silkscreen Top")
		(7 "B.SilkS" user "Ref Des/Silkscreen Bottom")
		(1 "F.Mask" user "Board Geometry/Soldermask Top")
		(3 "B.Mask" user "Board Geometry/Soldermask Bottom")
		(17 "Dwgs.User" user "User.Drawings")
		(19 "Cmts.User" user "User.Comments")
		(21 "Eco1.User" user "User.Eco1")
		(23 "Eco2.User" user "User.Eco2")
		(25 "Edge.Cuts" user "Board Geometry/Outline")
		(27 "Margin" user)
		(31 "F.CrtYd" user "Package Geometry/Place Bound Top")
		(29 "B.CrtYd" user "Package Geometry/Place Bound Bottom")
		(35 "F.Fab" user "Ref Des/Assembly Top")
		(33 "B.Fab" user "Ref Des/Assembly Bottom")
	)
	(footprint ""
		(layer "F.Cu")
		(at 190.8556 -127.635 180)
		(property "Reference" "R563"
			(at 0 0 180)
			(layer "F.SilkS")
			(hide yes)
			(effects
				(font
					(size 1.27 1.27)
				)
			)
		)
		(property "Value" "100KR2F-L1-GP"
			(at 0.064008 -3.993896 180)
			(unlocked yes)
			(layer "F.Fab")
			(hide yes)
			(effects
				(font
					(size 1.016 1.016)
					(thickness 0.1524)
				)
			)
		)
		(property "Device Type" "R402H16"
			(at 0.064008 -5.517896 180)
			(unlocked yes)
			(layer "F.Fab")
			(hide yes)
			(effects
				(font
					(size 1.016 1.016)
					(thickness 0.1524)
				)
			)
		)
		(duplicate_pad_numbers_are_jumpers no)
		(fp_line
			(start 0.508 -0.9398)
			(end -0.508 -0.9398)
			(stroke
				(width 0.1524)
				(type default)
			)
			(layer "F.SilkS")
		)
		(fp_line
			(start -0.508 -0.9398)
			(end -0.508 0.9398)
			(stroke
				(width 0.1524)
				(type default)
			)
			(layer "F.SilkS")
		)
		(fp_rect
			(start -0.508 0.9398)
			(end 0.508 -0.9398)
			(stroke
				(width 0)
				(type default)
			)
			(fill no)
			(layer "F.CrtYd")
		)
		(fp_rect
			(start -0.508 0.9398)
			(end 0.508 -0.9398)
			(stroke
				(width 0)
				(type default)
			)
			(fill no)
			(layer "F.Fab")
		)
		(pad "1" smd custom
			(at 0 -0.4445 180)
			(size 0.1397 0.1397)
			(layers "F.Cu" "F.Mask" "F.Paste")
			(net "VT235_VDES")
			(options
				(clearance outline)
				(anchor circle)
			)
			(primitives
				(gr_poly
					(pts
						(arc
							(start -0.1778 -0.2794)
							(mid -0.249642 -0.249642)
							(end -0.2794 -0.1778)
						)
						(arc
							(start -0.2794 0.1778)
							(mid -0.249642 0.249642)
							(end -0.1778 0.2794)
						)
						(arc
							(start 0.1778 0.2794)
							(mid 0.249642 0.249642)
							(end 0.2794 0.1778)
						)
						(arc
							(start 0.2794 -0.1778)
							(mid 0.249642 -0.249642)
							(end 0.1778 -0.2794)
						)
					)
					(width 0)
					(fill yes)
				)
			)
		)
		(pad "2" smd custom
			(at 0 0.4445 180)
			(size 0.1397 0.1397)
			(layers "F.Cu" "F.Mask" "F.Paste")
			(net "VT235_VREF")
			(options
				(clearance outline)
				(anchor circle)
			)
			(primitives
				(gr_poly
					(pts
						(arc
							(start -0.1778 -0.2794)
							(mid -0.249642 -0.249642)
							(end -0.2794 -0.1778)
						)
						(arc
							(start -0.2794 0.1778)
							(mid -0.249642 0.249642)
							(end -0.1778 0.2794)
						)
						(arc
							(start 0.1778 0.2794)
							(mid 0.249642 0.249642)
							(end 0.2794 0.1778)
						)
						(arc
							(start 0.2794 -0.1778)
							(mid 0.249642 -0.249642)
							(end 0.1778 -0.2794)
						)
					)
					(width 0)
					(fill yes)
				)
			)
		)
	)
	(footprint ""
		(layer "F.Cu")
		(at 46.449996 -131.747514 180)
		(property "Reference" "R265"
			(at 0 0 180)
			(layer "F.SilkS")
			(hide yes)
			(effects
				(font
					(size 1.27 1.27)
				)
			)
		)
		(property "Value" "4K7R2F-GP"
			(at 0.064008 -3.993896 180)
			(unlocked yes)
			(layer "F.Fab")
			(hide yes)
			(effects
				(font
					(size 1.016 1.016)
					(thickness 0.1524)
				)
			)
		)
		(property "Device Type" "R402H16"
			(at 0.064008 -5.517896 180)
			(unlocked yes)
			(layer "F.Fab")
			(hide yes)
			(effects
				(font
					(size 1.016 1.016)
					(thickness 0.1524)
				)
			)
		)
		(duplicate_pad_numbers_are_jumpers no)
		(fp_line
			(start 0.508 -0.9398)
			(end -0.508 -0.9398)
			(stroke
				(width 0.1524)
				(type default)
			)
			(layer "F.SilkS")
		)
		(fp_line
			(start -0.508 -0.9398)
			(end -0.508 0.9398)
			(stroke
				(width 0.1524)
				(type default)
			)
			(layer "F.SilkS")
		)
		(fp_rect
			(start -0.508 0.9398)
			(end 0.508 -0.9398)
			(stroke
				(width 0)
				(type default)
			)
			(fill no)
			(layer "F.CrtYd")
		)
		(fp_rect
			(start -0.508 0.9398)
			(end 0.508 -0.9398)
			(stroke
				(width 0)
				(type default)
			)
			(fill no)
			(layer "F.Fab")
		)
		(pad "1" smd custom
			(at 0 -0.4445 180)
			(size 0.1397 0.1397)
			(layers "F.Cu" "F.Mask" "F.Paste")
			(net "P3V3_STBY")
			(options
				(clearance outline)
				(anchor circle)
			)
			(primitives
				(gr_poly
					(pts
						(arc
							(start -0.1778 -0.2794)
							(mid -0.249642 -0.249642)
							(end -0.2794 -0.1778)
						)
						(arc
							(start -0.2794 0.1778)
							(mid -0.249642 0.249642)
							(end -0.1778 0.2794)
						)
						(arc
							(start 0.1778 0.2794)
							(mid 0.249642 0.249642)
							(end 0.2794 0.1778)
						)
						(arc
							(start 0.2794 -0.1778)
							(mid 0.249642 -0.249642)
							(end 0.1778 -0.2794)
						)
					)
					(width 0)
					(fill yes)
				)
			)
		)
		(pad "2" smd custom
			(at 0 0.4445 180)
			(size 0.1397 0.1397)
			(layers "F.Cu" "F.Mask" "F.Paste")
			(net "BMC_GPIOY3")
			(options
				(clearance outline)
				(anchor circle)
			)
			(primitives
				(gr_poly
					(pts
						(arc
							(start -0.1778 -0.2794)
							(mid -0.249642 -0.249642)
							(end -0.2794 -0.1778)
						)
						(arc
							(start -0.2794 0.1778)
							(mid -0.249642 0.249642)
							(end -0.1778 0.2794)
						)
						(arc
							(start 0.1778 0.2794)
							(mid 0.249642 0.249642)
							(end 0.2794 0.1778)
						)
						(arc
							(start 0.2794 -0.1778)
							(mid 0.249642 -0.249642)
							(end 0.1778 -0.2794)
						)
					)
					(width 0)
					(fill yes)
				)
			)
		)
	)
	(footprint ""
		(layer "F.Cu")
		(at 179.787804 -153.207466 180)
		(property "Reference" "R471"
			(at 0 0 180)
			(layer "F.SilkS")
			(hide yes)
			(effects
				(font
					(size 1.27 1.27)
				)
			)
		)
		(property "Value" "15KR2F-GP"
			(at 0.064008 -3.993896 180)
			(unlocked yes)
			(layer "F.Fab")
			(hide yes)
			(effects
				(font
					(size 1.016 1.016)
					(thickness 0.1524)
				)
			)
		)
		(property "Device Type" "R402H16"
			(at 0.064008 -5.517896 180)
			(unlocked yes)
			(layer "F.Fab")
			(hide yes)
			(effects
				(font
					(size 1.016 1.016)
					(thickness 0.1524)
				)
			)
		)
		(duplicate_pad_numbers_are_jumpers no)
		(fp_line
			(start 0.508 -0.9398)
			(end -0.508 -0.9398)
			(stroke
				(width 0.1524)
				(type default)
			)
			(layer "F.SilkS")
		)
		(fp_line
			(start -0.508 -0.9398)
			(end -0.508 0.9398)
			(stroke
				(width 0.1524)
				(type default)
			)
			(layer "F.SilkS")
		)
		(fp_rect
			(start -0.508 0.9398)
			(end 0.508 -0.9398)
			(stroke
				(width 0)
				(type default)
			)
			(fill no)
			(layer "F.CrtYd")
		)
		(fp_rect
			(start -0.508 0.9398)
			(end 0.508 -0.9398)
			(stroke
				(width 0)
				(type default)
			)
			(fill no)
			(layer "F.Fab")
		)
		(pad "1" smd custom
			(at 0 -0.4445 180)
			(size 0.1397 0.1397)
			(layers "F.Cu" "F.Mask" "F.Paste")
			(net "PWRGD_P5V_STBY")
			(options
				(clearance outline)
				(anchor circle)
			)
			(primitives
				(gr_poly
					(pts
						(arc
							(start -0.1778 -0.2794)
							(mid -0.249642 -0.249642)
							(end -0.2794 -0.1778)
						)
						(arc
							(start -0.2794 0.1778)
							(mid -0.249642 0.249642)
							(end -0.1778 0.2794)
						)
						(arc
							(start 0.1778 0.2794)
							(mid 0.249642 0.249642)
							(end 0.2794 0.1778)
						)
						(arc
							(start 0.2794 -0.1778)
							(mid 0.249642 -0.249642)
							(end 0.1778 -0.2794)
						)
					)
					(width 0)
					(fill yes)
				)
			)
		)
		(pad "2" smd custom
			(at 0 0.4445 180)
			(size 0.1397 0.1397)
			(layers "F.Cu" "F.Mask" "F.Paste")
			(net "GND")
			(options
				(clearance outline)
				(anchor circle)
			)
			(primitives
				(gr_poly
					(pts
						(arc
							(start -0.1778 -0.2794)
							(mid -0.249642 -0.249642)
							(end -0.2794 -0.1778)
						)
						(arc
							(start -0.2794 0.1778)
							(mid -0.249642 0.249642)
							(end -0.1778 0.2794)
						)
						(arc
							(start 0.1778 0.2794)
							(mid 0.249642 0.249642)
							(end 0.2794 0.1778)
						)
						(arc
							(start 0.2794 -0.1778)
							(mid 0.249642 -0.249642)
							(end 0.1778 -0.2794)
						)
					)
					(width 0)
					(fill yes)
				)
			)
		)
	)
	(footprint ""
		(layer "F.Cu")
		(at 65.641474 -179.37226)
		(property "Reference" "R81"
			(at 0 0 0)
			(layer "F.SilkS")
			(hide yes)
			(effects
				(font
					(size 1.27 1.27)
				)
			)
		)
		(property "Value" "4K75R2F-1-GP"
			(at 0.064008 -3.993896 0)
			(unlocked yes)
			(layer "F.Fab")
			(hide yes)
			(effects
				(font
					(size 1.016 1.016)
					(thickness 0.1524)
				)
			)
		)
		(property "Device Type" "R402H16"
			(at 0.064008 -5.517896 0)
			(unlocked yes)
			(layer "F.Fab")
			(hide yes)
			(effects
				(font
					(size 1.016 1.016)
					(thickness 0.1524)
				)
			)
		)
		(duplicate_pad_numbers_are_jumpers no)
		(fp_line
			(start -0.508 -0.9398)
			(end -0.508 0.9398)
			(stroke
				(width 0.1524)
				(type default)
			)
			(layer "F.SilkS")
		)
		(fp_line
			(start 0.508 -0.9398)
			(end -0.508 -0.9398)
			(stroke
				(width 0.1524)
				(type default)
			)
			(layer "F.SilkS")
		)
		(fp_rect
			(start -0.508 0.9398)
			(end 0.508 -0.9398)
			(stroke
				(width 0)
				(type default)
			)
			(fill no)
			(layer "F.CrtYd")
		)
		(fp_rect
			(start -0.508 0.9398)
			(end 0.508 -0.9398)
			(stroke
				(width 0)
				(type default)
			)
			(fill no)
			(layer "F.Fab")
		)
		(pad "1" smd custom
			(at 0 -0.4445)
			(size 0.1397 0.1397)
			(layers "F.Cu" "F.Mask" "F.Paste")
			(net "P3V3_STBY")
			(options
				(clearance outline)
				(anchor circle)
			)
			(primitives
				(gr_poly
					(pts
						(arc
							(start -0.1778 -0.2794)
							(mid -0.249642 -0.249642)
							(end -0.2794 -0.1778)
						)
						(arc
							(start -0.2794 0.1778)
							(mid -0.249642 0.249642)
							(end -0.1778 0.2794)
						)
						(arc
							(start 0.1778 0.2794)
							(mid 0.249642 0.249642)
							(end 0.2794 0.1778)
						)
						(arc
							(start 0.2794 -0.1778)
							(mid 0.249642 -0.249642)
							(end 0.1778 -0.2794)
						)
					)
					(width 0)
					(fill yes)
				)
			)
		)
		(pad "2" smd custom
			(at 0 0.4445)
			(size 0.1397 0.1397)
			(layers "F.Cu" "F.Mask" "F.Paste")
			(net "VREF_2V2")
			(options
				(clearance outline)
				(anchor circle)
			)
			(primitives
				(gr_poly
					(pts
						(arc
							(start -0.1778 -0.2794)
							(mid -0.249642 -0.249642)
							(end -0.2794 -0.1778)
						)
						(arc
							(start -0.2794 0.1778)
							(mid -0.249642 0.249642)
							(end -0.1778 0.2794)
						)
						(arc
							(start 0.1778 0.2794)
							(mid 0.249642 0.249642)
							(end 0.2794 0.1778)
						)
						(arc
							(start 0.2794 -0.1778)
							(mid 0.249642 -0.249642)
							(end 0.1778 -0.2794)
						)
					)
					(width 0)
					(fill yes)
				)
			)
		)
	)
	(footprint ""
		(layer "F.Cu")
		(at 112.84839 -5.577078 -90)
		(property "Reference" "R456"
			(at 0 0 270)
			(layer "F.SilkS")
			(hide yes)
			(effects
				(font
					(size 1.27 1.27)
				)
			)
		)
		(property "Value" "0R2J-2-GP"
			(at 0.064008 -3.993896 270)
			(unlocked yes)
			(layer "F.Fab")
			(hide yes)
			(effects
				(font
					(size 1.016 1.016)
					(thickness 0.1524)
				)
			)
		)
		(property "Device Type" "R402H16"
			(at 0.064008 -5.517896 270)
			(unlocked yes)
			(layer "F.Fab")
			(hide yes)
			(effects
				(font
					(size 1.016 1.016)
					(thickness 0.1524)
				)
			)
		)
		(duplicate_pad_numbers_are_jumpers no)
		(fp_line
			(start -0.508 -0.9398)
			(end -0.508 0.9398)
			(stroke
				(width 0.1524)
				(type default)
			)
			(layer "F.SilkS")
		)
		(fp_line
			(start 0.508 -0.9398)
			(end -0.508 -0.9398)
			(stroke
				(width 0.1524)
				(type default)
			)
			(layer "F.SilkS")
		)
		(fp_rect
			(start -0.508 0.9398)
			(end 0.508 -0.9398)
			(stroke
				(width 0)
				(type default)
			)
			(fill no)
			(layer "F.CrtYd")
		)
		(fp_rect
			(start -0.508 0.9398)
			(end 0.508 -0.9398)
			(stroke
				(width 0)
				(type default)
			)
			(fill no)
			(layer "F.Fab")
		)
		(pad "1" smd custom
			(at 0 -0.4445 270)
			(size 0.1397 0.1397)
			(layers "F.Cu" "F.Mask" "F.Paste")
			(net "MB0_SPISS_PD")
			(options
				(clearance outline)
				(anchor circle)
			)
			(primitives
				(gr_poly
					(pts
						(arc
							(start -0.1778 -0.2794)
							(mid -0.249642 -0.249642)
							(end -0.2794 -0.1778)
						)
						(arc
							(start -0.2794 0.1778)
							(mid -0.249642 0.249642)
							(end -0.1778 0.2794)
						)
						(arc
							(start 0.1778 0.2794)
							(mid 0.249642 0.249642)
							(end 0.2794 0.1778)
						)
						(arc
							(start 0.2794 -0.1778)
							(mid 0.249642 -0.249642)
							(end 0.1778 -0.2794)
						)
					)
					(width 0)
					(fill yes)
				)
			)
		)
		(pad "2" smd custom
			(at 0 0.4445 270)
			(size 0.1397 0.1397)
			(layers "F.Cu" "F.Mask" "F.Paste")
			(net "AGND_CURRENT_MON")
			(options
				(clearance outline)
				(anchor circle)
			)
			(primitives
				(gr_poly
					(pts
						(arc
							(start -0.1778 -0.2794)
							(mid -0.249642 -0.249642)
							(end -0.2794 -0.1778)
						)
						(arc
							(start -0.2794 0.1778)
							(mid -0.249642 0.249642)
							(end -0.1778 0.2794)
						)
						(arc
							(start 0.1778 0.2794)
							(mid 0.249642 0.249642)
							(end 0.2794 0.1778)
						)
						(arc
							(start 0.2794 -0.1778)
							(mid 0.249642 -0.249642)
							(end 0.1778 -0.2794)
						)
					)
					(width 0)
					(fill yes)
				)
			)
		)
	)
	(footprint ""
		(layer "F.Cu")
		(at 82.94116 -157.3276 90)
		(property "Reference" "C238"
			(at 0 0 90)
			(layer "F.SilkS")
			(hide yes)
			(effects
				(font
					(size 1.27 1.27)
				)
			)
		)
		(property "Value" "SC10U6D3V5KX-4GP"
			(at -0.0762 -6.1214 90)
			(unlocked yes)
			(layer "F.Fab")
			(hide yes)
			(effects
				(font
					(size 1.016 1.016)
					(thickness 0.1524)
				)
			)
		)
		(property "Device Type" "C805H58"
			(at -0.0762 -8.1534 90)
			(unlocked yes)
			(layer "F.Fab")
			(hide yes)
			(effects
				(font
					(size 1.016 1.016)
					(thickness 0.1524)
				)
			)
		)
		(duplicate_pad_numbers_are_jumpers no)
		(fp_line
			(start 0.635 0)
			(end -0.635 0)
			(stroke
				(width 0.508)
				(type default)
			)
			(layer "F.SilkS")
		)
		(fp_rect
			(start -0.9652 1.778)
			(end 0.9652 -1.778)
			(stroke
				(width 0)
				(type default)
			)
			(fill no)
			(layer "F.CrtYd")
		)
		(fp_poly
			(pts
				(xy -0.9652 -1.778) (xy 0.9652 -1.778) (xy 0.9652 1.778) (xy -0.9652 1.778)
			)
			(stroke
				(width 0)
				(type default)
			)
			(fill no)
			(layer "F.Fab")
		)
		(pad "1" smd rect
			(at 0 -0.9652 90)
			(size 1.397 1.143)
			(layers "F.Cu" "F.Mask" "F.Paste")
			(net "TPS74801_P1V15_STBY_OUT")
		)
		(pad "2" smd rect
			(at 0 0.9652 90)
			(size 1.397 1.143)
			(layers "F.Cu" "F.Mask" "F.Paste")
			(net "GND")
		)
	)
	(footprint ""
		(layer "F.Cu")
		(at 61.28258 -140.349732 90)
		(property "Reference" "R271"
			(at 0 0 90)
			(layer "F.SilkS")
			(hide yes)
			(effects
				(font
					(size 1.27 1.27)
				)
			)
		)
		(property "Value" "4K7R2F-GP"
			(at 0.064008 -3.993896 90)
			(unlocked yes)
			(layer "F.Fab")
			(hide yes)
			(effects
				(font
					(size 1.016 1.016)
					(thickness 0.1524)
				)
			)
		)
		(property "Device Type" "R402H16"
			(at 0.064008 -5.517896 90)
			(unlocked yes)
			(layer "F.Fab")
			(hide yes)
			(effects
				(font
					(size 1.016 1.016)
					(thickness 0.1524)
				)
			)
		)
		(duplicate_pad_numbers_are_jumpers no)
		(fp_line
			(start 0.508 -0.9398)
			(end -0.508 -0.9398)
			(stroke
				(width 0.1524)
				(type default)
			)
			(layer "F.SilkS")
		)
		(fp_line
			(start -0.508 -0.9398)
			(end -0.508 0.9398)
			(stroke
				(width 0.1524)
				(type default)
			)
			(layer "F.SilkS")
		)
		(fp_rect
			(start -0.508 0.9398)
			(end 0.508 -0.9398)
			(stroke
				(width 0)
				(type default)
			)
			(fill no)
			(layer "F.CrtYd")
		)
		(fp_rect
			(start -0.508 0.9398)
			(end 0.508 -0.9398)
			(stroke
				(width 0)
				(type default)
			)
			(fill no)
			(layer "F.Fab")
		)
		(pad "1" smd custom
			(at 0 -0.4445 90)
			(size 0.1397 0.1397)
			(layers "F.Cu" "F.Mask" "F.Paste")
			(net "BMC_TO_EXP_RESET_OUT")
			(options
				(clearance outline)
				(anchor circle)
			)
			(primitives
				(gr_poly
					(pts
						(arc
							(start -0.1778 -0.2794)
							(mid -0.249642 -0.249642)
							(end -0.2794 -0.1778)
						)
						(arc
							(start -0.2794 0.1778)
							(mid -0.249642 0.249642)
							(end -0.1778 0.2794)
						)
						(arc
							(start 0.1778 0.2794)
							(mid 0.249642 0.249642)
							(end 0.2794 0.1778)
						)
						(arc
							(start 0.2794 -0.1778)
							(mid 0.249642 -0.249642)
							(end 0.1778 -0.2794)
						)
					)
					(width 0)
					(fill yes)
				)
			)
		)
		(pad "2" smd custom
			(at 0 0.4445 90)
			(size 0.1397 0.1397)
			(layers "F.Cu" "F.Mask" "F.Paste")
			(net "P3V3_STBY")
			(options
				(clearance outline)
				(anchor circle)
			)
			(primitives
				(gr_poly
					(pts
						(arc
							(start -0.1778 -0.2794)
							(mid -0.249642 -0.249642)
							(end -0.2794 -0.1778)
						)
						(arc
							(start -0.2794 0.1778)
							(mid -0.249642 0.249642)
							(end -0.1778 0.2794)
						)
						(arc
							(start 0.1778 0.2794)
							(mid 0.249642 0.249642)
							(end 0.2794 0.1778)
						)
						(arc
							(start 0.2794 -0.1778)
							(mid 0.249642 -0.249642)
							(end 0.1778 -0.2794)
						)
					)
					(width 0)
					(fill yes)
				)
			)
		)
	)
)
